# BASEBOARD_FAB2 (Tioga Pass) — schematic netlist excerpt (pin names and nets, part order shuffled) for the footprints in the layout excerpt that follows; sources: Cadence DE-HDL packaged netlist, KiCad conversion of Wiwynn_Tioga_Pass_MB.brd

C1A20  CAP_A  0.1UF 16V 10% X7R  pkg 0402V  page 227 : A = VR_FET_SW_P12V_STBY_PVDDQ_KLM ; B = GND
C2D23  CAP_A  22.0UF 4V 20% X6S  pkg 0603V  page 76 : A = PVCCIN_CPU1 ; B = GND
C8F18  CAP  15.0PF 50V 5% COG  pkg 0402LF  page 101 : A = XTAL_CK_MNG_IN ; B = GND

(kicad_pcb
	(version 20260206)
	(generator "pcbnew")
	(generator_version "10.0")
	(general
		(thickness 1.6)
		(legacy_teardrops no)
	)
	(paper "A4")
	(title_block
		(title "Wiwynn_Tioga_Pass_MB.brd")
		(comment 1 "Tioga Pass / footprints 901-903 of 4770")
	)
	(layers
		(0 "F.Cu" signal "TOP")
		(4 "In1.Cu" signal "L2GND")
		(6 "In2.Cu" signal "L3")
		(8 "In3.Cu" signal "L4GND")
		(10 "In4.Cu" signal "L5")
		(12 "In5.Cu" signal "L6GND")
		(14 "In6.Cu" signal "L7VCC")
		(16 "In7.Cu" signal "L8VCC")
		(18 "In8.Cu" signal "L9GND")
		(20 "In9.Cu" signal "L10")
		(22 "In10.Cu" signal "L11GND")
		(24 "In11.Cu" signal "L12")
		(26 "In12.Cu" signal "L13GND")
		(2 "B.Cu" signal "BOTTOM")
		(9 "F.Adhes" user "F.Adhesive")
		(11 "B.Adhes" user "B.Adhesive")
		(13 "F.Paste" user "Package Geometry/Pastemask Top")
		(15 "B.Paste" user "Package Geometry/Pastemask Bottom")
		(5 "F.SilkS" user "Ref Des/Silkscreen Top")
		(7 "B.SilkS" user "Ref Des/Silkscreen Bottom")
		(1 "F.Mask" user "Board Geometry/Soldermask Top")
		(3 "B.Mask" user "Board Geometry/Soldermask Bottom")
		(17 "Dwgs.User" user "User.Drawings")
		(19 "Cmts.User" user "User.Comments")
		(21 "Eco1.User" user "User.Eco1")
		(23 "Eco2.User" user "User.Eco2")
		(25 "Edge.Cuts" user "Board Geometry/Outline")
		(27 "Margin" user)
		(31 "F.CrtYd" user "Package Geometry/Place Bound Top")
		(29 "B.CrtYd" user "Package Geometry/Place Bound Bottom")
		(35 "F.Fab" user "Ref Des/Assembly Top")
		(33 "B.Fab" user "Ref Des/Assembly Bottom")
	)
	(footprint ""
		(layer "F.Cu")
		(at 1.315212 -150.678896 90)
		(property "Reference" "C1A20"
			(at 0 0 90)
			(layer "F.SilkS")
			(hide yes)
			(effects
				(font
					(size 1.27 1.27)
				)
			)
		)
		(property "Value" ""
			(at 0 0 90)
			(layer "F.Fab")
			(effects
				(font
					(size 1.27 1.27)
				)
			)
		)
		(duplicate_pad_numbers_are_jumpers no)
		(fp_rect
			(start 0.3048 -0.1016)
			(end -0.3048 0.9906)
			(stroke
				(width 0)
				(type default)
			)
			(fill no)
			(layer "F.CrtYd")
		)
		(fp_line
			(start 0.3048 -0.1016)
			(end -0.3048 -0.1016)
			(stroke
				(width 0.1)
				(type default)
			)
			(layer "F.Fab")
		)
		(fp_line
			(start -0.3048 -0.1016)
			(end -0.3048 0.9906)
			(stroke
				(width 0.1)
				(type default)
			)
			(layer "F.Fab")
		)
		(fp_line
			(start 0.3048 0.9906)
			(end 0.3048 -0.1016)
			(stroke
				(width 0.1)
				(type default)
			)
			(layer "F.Fab")
		)
		(fp_line
			(start -0.3048 0.9906)
			(end 0.3048 0.9906)
			(stroke
				(width 0.1)
				(type default)
			)
			(layer "F.Fab")
		)
		(pad "1" smd rect
			(at 0 0 90)
			(size 0.508 0.508)
			(layers "F.Cu" "F.Mask" "F.Paste")
			(net "VR_FET_SW_P12V_STBY_PVDDQ_KLM")
		)
		(pad "2" smd rect
			(at 0 0.889 90)
			(size 0.508 0.508)
			(layers "F.Cu" "F.Mask" "F.Paste")
			(net "GND")
		)
		(zone
			(layer "F.Cu")
			(hatch none 0.5)
			(connect_pads
				(clearance 0)
			)
			(min_thickness 0.25)
			(keepout
				(tracks allowed)
				(vias not_allowed)
				(pads allowed)
				(copperpour not_allowed)
				(footprints allowed)
			)
			(placement
				(enabled no)
				(sheetname "")
			)
			(fill
				(thermal_gap 0.5)
				(thermal_bridge_width 0.5)
				(island_removal_mode 0)
			)
			(polygon
				(pts
					(xy 1.569212 -150.932896) (xy 1.569212 -150.424896) (xy 1.950212 -150.424896) (xy 1.950212 -150.932896)
				)
			)
		)
		(zone
			(layer "F.Cu")
			(hatch none 0.5)
			(connect_pads
				(clearance 0)
			)
			(min_thickness 0.25)
			(keepout
				(tracks not_allowed)
				(vias allowed)
				(pads allowed)
				(copperpour not_allowed)
				(footprints allowed)
			)
			(placement
				(enabled no)
				(sheetname "")
			)
			(fill
				(thermal_gap 0.5)
				(thermal_bridge_width 0.5)
				(island_removal_mode 0)
			)
			(polygon
				(pts
					(xy 1.569212 -150.932896) (xy 1.569212 -150.424896) (xy 1.950212 -150.424896) (xy 1.950212 -150.932896)
				)
			)
		)
	)
	(footprint ""
		(layer "F.Cu")
		(at 98.18624 -77.636116)
		(property "Reference" "C2D23"
			(at 0 0 0)
			(layer "F.SilkS")
			(hide yes)
			(effects
				(font
					(size 1.27 1.27)
				)
			)
		)
		(property "Value" ""
			(at 0 0 0)
			(layer "F.Fab")
			(effects
				(font
					(size 1.27 1.27)
				)
			)
		)
		(duplicate_pad_numbers_are_jumpers no)
		(fp_poly
			(pts
				(xy -0.4953 -0.2032) (xy 0.4953 -0.2032) (xy 0.4953 1.6002) (xy -0.4953 1.6002)
			)
			(stroke
				(width 0)
				(type default)
			)
			(fill no)
			(layer "F.CrtYd")
		)
		(fp_line
			(start -0.4953 -0.2032)
			(end 0.4953 -0.2032)
			(stroke
				(width 0.1)
				(type default)
			)
			(layer "F.Fab")
		)
		(fp_line
			(start -0.4953 1.6002)
			(end -0.4953 -0.2032)
			(stroke
				(width 0.1)
				(type default)
			)
			(layer "F.Fab")
		)
		(fp_line
			(start 0.4953 -0.2032)
			(end 0.4953 1.6002)
			(stroke
				(width 0.1)
				(type default)
			)
			(layer "F.Fab")
		)
		(fp_line
			(start 0.4953 1.6002)
			(end -0.4953 1.6002)
			(stroke
				(width 0.1)
				(type default)
			)
			(layer "F.Fab")
		)
		(pad "1" smd rect
			(at 0 0)
			(size 0.762 0.889)
			(layers "F.Cu" "F.Mask" "F.Paste")
			(net "PVCCIN_CPU1")
		)
		(pad "2" smd rect
			(at 0 1.397)
			(size 0.762 0.889)
			(layers "F.Cu" "F.Mask" "F.Paste")
			(net "GND")
		)
		(zone
			(layer "F.Cu")
			(hatch none 0.5)
			(connect_pads
				(clearance 0)
			)
			(min_thickness 0.25)
			(keepout
				(tracks not_allowed)
				(vias allowed)
				(pads allowed)
				(copperpour not_allowed)
				(footprints allowed)
			)
			(placement
				(enabled no)
				(sheetname "")
			)
			(fill
				(thermal_gap 0.5)
				(thermal_bridge_width 0.5)
				(island_removal_mode 0)
			)
			(polygon
				(pts
					(xy 97.80524 -77.191616) (xy 98.56724 -77.191616) (xy 98.56724 -76.683616) (xy 97.80524 -76.683616)
				)
			)
		)
	)
	(footprint ""
		(layer "F.Cu")
		(at 482.6508 -32.2834)
		(property "Reference" "C8F18"
			(at 0 0 0)
			(layer "F.SilkS")
			(hide yes)
			(effects
				(font
					(size 1.27 1.27)
				)
			)
		)
		(property "Value" ""
			(at 0 0 0)
			(layer "F.Fab")
			(effects
				(font
					(size 1.27 1.27)
				)
			)
		)
		(duplicate_pad_numbers_are_jumpers no)
		(fp_poly
			(pts
				(xy 0.3048 -0.1016) (xy 0.3048 0.9906) (xy -0.3048 0.9906) (xy -0.3048 -0.1016)
			)
			(stroke
				(width 0)
				(type default)
			)
			(fill no)
			(layer "F.CrtYd")
		)
		(fp_line
			(start -0.3048 -0.1016)
			(end -0.3048 0.9906)
			(stroke
				(width 0.1)
				(type default)
			)
			(layer "F.Fab")
		)
		(fp_line
			(start -0.3048 0.9906)
			(end 0.3048 0.9906)
			(stroke
				(width 0.1)
				(type default)
			)
			(layer "F.Fab")
		)
		(fp_line
			(start 0.3048 -0.1016)
			(end -0.3048 -0.1016)
			(stroke
				(width 0.1)
				(type default)
			)
			(layer "F.Fab")
		)
		(fp_line
			(start 0.3048 0.9906)
			(end 0.3048 -0.1016)
			(stroke
				(width 0.1)
				(type default)
			)
			(layer "F.Fab")
		)
		(pad "1" smd rect
			(at 0 0)
			(size 0.508 0.508)
			(layers "F.Cu" "F.Mask" "F.Paste")
			(net "XTAL_CK_MNG_IN")
		)
		(pad "2" smd rect
			(at 0 0.889)
			(size 0.508 0.508)
			(layers "F.Cu" "F.Mask" "F.Paste")
			(net "GND")
		)
		(zone
			(layer "F.Cu")
			(hatch none 0.5)
			(connect_pads
				(clearance 0)
			)
			(min_thickness 0.25)
			(keepout
				(tracks allowed)
				(vias not_allowed)
				(pads allowed)
				(copperpour not_allowed)
				(footprints allowed)
			)
			(placement
				(enabled no)
				(sheetname "")
			)
			(fill
				(thermal_gap 0.5)
				(thermal_bridge_width 0.5)
				(island_removal_mode 0)
			)
			(polygon
				(pts
					(xy 482.3968 -32.0294) (xy 482.9048 -32.0294) (xy 482.9048 -31.6484) (xy 482.3968 -31.6484)
				)
			)
		)
		(zone
			(layer "F.Cu")
			(hatch none 0.5)
			(connect_pads
				(clearance 0)
			)
			(min_thickness 0.25)
			(keepout
				(tracks not_allowed)
				(vias allowed)
				(pads allowed)
				(copperpour not_allowed)
				(footprints allowed)
			)
			(placement
				(enabled no)
				(sheetname "")
			)
			(fill
				(thermal_gap 0.5)
				(thermal_bridge_width 0.5)
				(island_removal_mode 0)
			)
			(polygon
				(pts
					(xy 482.3968 -31.6484) (xy 482.9048 -31.6484) (xy 482.9048 -32.0294) (xy 482.3968 -32.0294)
				)
			)
		)
	)
)
